# S9S_MB_2U (Grand Teton) — schematic netlist excerpt (pin names and nets, part order shuffled) for the footprints in the layout excerpt that follows; sources: Cadence DE-HDL packaged netlist, KiCad conversion of 03242023_DA0F0TMBIJ0_F0T_Motherboard_J_brd_V01_OCP.brd

PR225  Q_RES  8.87K 1% EMPTY  pkg 0402LF  page 289 : A = PVCCFA_EHV_FIVRA_CPU1_LSET1 ; B = GND
R2846  Q_RES  33.2 1% CHIP  pkg 0402LF  page 213 : A = BIC_MONITER_ISO ; B = BIC_MONITER_ISO_R

(kicad_pcb
	(version 20260206)
	(generator "pcbnew")
	(generator_version "10.0")
	(general
		(thickness 1.6)
		(legacy_teardrops no)
	)
	(paper "A4")
	(title_block
		(title "03242023_DA0F0TMBIJ0_F0T_Motherboard_J_brd_V01_OCP.brd")
		(comment 1 "Grand Teton / footprints 1942-1943 of 6105")
	)
	(layers
		(0 "F.Cu" signal "TOP")
		(4 "In1.Cu" signal "GND")
		(6 "In2.Cu" signal "IN1")
		(8 "In3.Cu" signal "GND1")
		(10 "In4.Cu" signal "IN2")
		(12 "In5.Cu" signal "GND2")
		(14 "In6.Cu" signal "IN3")
		(16 "In7.Cu" signal "GND3")
		(18 "In8.Cu" signal "VCC")
		(20 "In9.Cu" signal "VCC1")
		(22 "In10.Cu" signal "GND4")
		(24 "In11.Cu" signal "IN4")
		(26 "In12.Cu" signal "GND5")
		(28 "In13.Cu" signal "IN5")
		(30 "In14.Cu" signal "GND6")
		(32 "In15.Cu" signal "IN6")
		(34 "In16.Cu" signal "GND7")
		(2 "B.Cu" signal "BOTTOM")
		(9 "F.Adhes" user "F.Adhesive")
		(11 "B.Adhes" user "B.Adhesive")
		(13 "F.Paste" user "Package Geometry/Pastemask Top")
		(15 "B.Paste" user "Package Geometry/Pastemask Bottom")
		(5 "F.SilkS" user "Ref Des/Silkscreen Top")
		(7 "B.SilkS" user "Ref Des/Silkscreen Bottom")
		(1 "F.Mask" user "Board Geometry/Soldermask Top")
		(3 "B.Mask" user "Board Geometry/Soldermask Bottom")
		(17 "Dwgs.User" user "User.Drawings")
		(19 "Cmts.User" user "User.Comments")
		(21 "Eco1.User" user "User.Eco1")
		(23 "Eco2.User" user "User.Eco2")
		(25 "Edge.Cuts" user "Board Geometry/Outline")
		(27 "Margin" user)
		(31 "F.CrtYd" user "Package Geometry/Place Bound Top")
		(29 "B.CrtYd" user "Package Geometry/Place Bound Bottom")
		(35 "F.Fab" user "Ref Des/Assembly Top")
		(33 "B.Fab" user "Ref Des/Assembly Bottom")
	)
	(footprint ""
		(layer "F.Cu")
		(at 170.732958 -358.698292)
		(property "Reference" "PR225"
			(at 0 0 0)
			(layer "F.SilkS")
			(hide yes)
			(effects
				(font
					(size 1.27 1.27)
				)
			)
		)
		(property "Value" ""
			(at 0 0 0)
			(layer "F.Fab")
			(effects
				(font
					(size 1.27 1.27)
				)
			)
		)
		(duplicate_pad_numbers_are_jumpers no)
		(fp_line
			(start -0.7874 -0.4064)
			(end 0.7874 -0.4064)
			(stroke
				(width 0.1524)
				(type default)
			)
			(layer "F.SilkS")
		)
		(fp_line
			(start -0.7874 0.4064)
			(end -0.7874 -0.4064)
			(stroke
				(width 0.1524)
				(type default)
			)
			(layer "F.SilkS")
		)
		(fp_line
			(start 0.7874 -0.4064)
			(end 0.7874 0.4064)
			(stroke
				(width 0.1524)
				(type default)
			)
			(layer "F.SilkS")
		)
		(fp_line
			(start 0.7874 0.4064)
			(end -0.7874 0.4064)
			(stroke
				(width 0.1524)
				(type default)
			)
			(layer "F.SilkS")
		)
		(fp_line
			(start -0.67945 -0.305054)
			(end -0.12065 -0.305054)
			(stroke
				(width 0.1)
				(type default)
			)
			(layer "F.Fab")
		)
		(fp_line
			(start -0.67945 0.3048)
			(end -0.67945 -0.305054)
			(stroke
				(width 0.1)
				(type default)
			)
			(layer "F.Fab")
		)
		(fp_line
			(start -0.12065 -0.305054)
			(end -0.12065 -0.2794)
			(stroke
				(width 0.1)
				(type default)
			)
			(layer "F.Fab")
		)
		(fp_line
			(start -0.12065 -0.2794)
			(end 0.12065 -0.2794)
			(stroke
				(width 0.1)
				(type default)
			)
			(layer "F.Fab")
		)
		(fp_line
			(start -0.12065 0.2794)
			(end -0.12065 0.3048)
			(stroke
				(width 0.1)
				(type default)
			)
			(layer "F.Fab")
		)
		(fp_line
			(start -0.12065 0.3048)
			(end -0.67945 0.3048)
			(stroke
				(width 0.1)
				(type default)
			)
			(layer "F.Fab")
		)
		(fp_line
			(start 0.120396 0.2794)
			(end -0.12065 0.2794)
			(stroke
				(width 0.1)
				(type default)
			)
			(layer "F.Fab")
		)
		(fp_line
			(start 0.120396 0.3048)
			(end 0.120396 0.2794)
			(stroke
				(width 0.1)
				(type default)
			)
			(layer "F.Fab")
		)
		(fp_line
			(start 0.12065 -0.3048)
			(end 0.67945 -0.3048)
			(stroke
				(width 0.1)
				(type default)
			)
			(layer "F.Fab")
		)
		(fp_line
			(start 0.12065 -0.2794)
			(end 0.12065 -0.3048)
			(stroke
				(width 0.1)
				(type default)
			)
			(layer "F.Fab")
		)
		(fp_line
			(start 0.67945 -0.3048)
			(end 0.67945 0.3048)
			(stroke
				(width 0.1)
				(type default)
			)
			(layer "F.Fab")
		)
		(fp_line
			(start 0.67945 0.3048)
			(end 0.120396 0.3048)
			(stroke
				(width 0.1)
				(type default)
			)
			(layer "F.Fab")
		)
		(pad "1" smd circle
			(at -0.40005 0)
			(size 0 0)
			(layers "F.Cu" "F.Mask" "F.Paste")
			(net "PVCCFA_EHV_FIVRA_CPU1_LSET1")
		)
		(pad "2" smd circle
			(at 0.40005 0)
			(size 0 0)
			(layers "F.Cu" "F.Mask" "F.Paste")
			(net "GND")
		)
	)
	(footprint ""
		(layer "F.Cu")
		(at 160.83788 -104.485948)
		(property "Reference" "R2846"
			(at 0 0 0)
			(layer "F.SilkS")
			(hide yes)
			(effects
				(font
					(size 1.27 1.27)
				)
			)
		)
		(property "Value" ""
			(at 0 0 0)
			(layer "F.Fab")
			(effects
				(font
					(size 1.27 1.27)
				)
			)
		)
		(duplicate_pad_numbers_are_jumpers no)
		(fp_line
			(start -0.7874 -0.4064)
			(end 0.7874 -0.4064)
			(stroke
				(width 0.1524)
				(type default)
			)
			(layer "F.SilkS")
		)
		(fp_line
			(start -0.7874 0.4064)
			(end -0.7874 -0.4064)
			(stroke
				(width 0.1524)
				(type default)
			)
			(layer "F.SilkS")
		)
		(fp_line
			(start 0.7874 -0.4064)
			(end 0.7874 0.4064)
			(stroke
				(width 0.1524)
				(type default)
			)
			(layer "F.SilkS")
		)
		(fp_line
			(start 0.7874 0.4064)
			(end -0.7874 0.4064)
			(stroke
				(width 0.1524)
				(type default)
			)
			(layer "F.SilkS")
		)
		(fp_line
			(start -0.67945 -0.305054)
			(end -0.12065 -0.305054)
			(stroke
				(width 0.1)
				(type default)
			)
			(layer "F.Fab")
		)
		(fp_line
			(start -0.67945 0.3048)
			(end -0.67945 -0.305054)
			(stroke
				(width 0.1)
				(type default)
			)
			(layer "F.Fab")
		)
		(fp_line
			(start -0.12065 -0.305054)
			(end -0.12065 -0.2794)
			(stroke
				(width 0.1)
				(type default)
			)
			(layer "F.Fab")
		)
		(fp_line
			(start -0.12065 -0.2794)
			(end 0.12065 -0.2794)
			(stroke
				(width 0.1)
				(type default)
			)
			(layer "F.Fab")
		)
		(fp_line
			(start -0.12065 0.2794)
			(end -0.12065 0.3048)
			(stroke
				(width 0.1)
				(type default)
			)
			(layer "F.Fab")
		)
		(fp_line
			(start -0.12065 0.3048)
			(end -0.67945 0.3048)
			(stroke
				(width 0.1)
				(type default)
			)
			(layer "F.Fab")
		)
		(fp_line
			(start 0.120396 0.2794)
			(end -0.12065 0.2794)
			(stroke
				(width 0.1)
				(type default)
			)
			(layer "F.Fab")
		)
		(fp_line
			(start 0.120396 0.3048)
			(end 0.120396 0.2794)
			(stroke
				(width 0.1)
				(type default)
			)
			(layer "F.Fab")
		)
		(fp_line
			(start 0.12065 -0.3048)
			(end 0.67945 -0.3048)
			(stroke
				(width 0.1)
				(type default)
			)
			(layer "F.Fab")
		)
		(fp_line
			(start 0.12065 -0.2794)
			(end 0.12065 -0.3048)
			(stroke
				(width 0.1)
				(type default)
			)
			(layer "F.Fab")
		)
		(fp_line
			(start 0.67945 -0.3048)
			(end 0.67945 0.3048)
			(stroke
				(width 0.1)
				(type default)
			)
			(layer "F.Fab")
		)
		(fp_line
			(start 0.67945 0.3048)
			(end 0.120396 0.3048)
			(stroke
				(width 0.1)
				(type default)
			)
			(layer "F.Fab")
		)
		(pad "1" smd circle
			(at -0.40005 0)
			(size 0 0)
			(layers "F.Cu" "F.Mask" "F.Paste")
			(net "BIC_MONITER_ISO")
		)
		(pad "2" smd circle
			(at 0.40005 0)
			(size 0 0)
			(layers "F.Cu" "F.Mask" "F.Paste")
			(net "BIC_MONITER_ISO_R")
		)
	)
)
